#ISCELL
  pure_quanta quanta_title_block_c *
  *
#CELL
  pure_quanta pt5161lrs *
  page406_i1
#ISCELL
  standard tap *
  page406_i10
#ISCELL
  standard tap *
  page406_i11
#ISCELL
  standard tap *
  page406_i12
#ISCELL
  standard tap *
  page406_i13
#ISCELL
  standard tap *
  page406_i14
#ISCELL
  standard tap *
  page406_i15
#ISCELL
  standard tap *
  page406_i16
#ISCELL
  standard tap *
  page406_i17
#ISCELL
  standard offpage *
  page406_i18
#ISCELL
  standard offpage *
  page406_i19
#ISCELL
  standard tap *
  page406_i2
#ISCELL
  standard tap *
  page406_i20
#ISCELL
  standard tap *
  page406_i21
#ISCELL
  standard tap *
  page406_i22
#ISCELL
  standard tap *
  page406_i23
#ISCELL
  standard tap *
  page406_i24
#ISCELL
  standard tap *
  page406_i25
#ISCELL
  standard tap *
  page406_i26
#ISCELL
  standard tap *
  page406_i27
#ISCELL
  standard tap *
  page406_i28
#ISCELL
  standard tap *
  page406_i29
#ISCELL
  standard tap *
  page406_i3
#ISCELL
  standard tap *
  page406_i30
#ISCELL
  standard tap *
  page406_i31
#ISCELL
  standard tap *
  page406_i32
#ISCELL
  standard tap *
  page406_i33
#ISCELL
  standard tap *
  page406_i34
#ISCELL
  standard tap *
  page406_i35
#ISCELL
  standard offpage *
  page406_i36
#ISCELL
  standard offpage *
  page406_i37
#CELL
  pure_quanta pt5161lrs *
  page406_i38
#ISCELL
  standard tap *
  page406_i4
#ISCELL
  standard tap *
  page406_i5
#ISCELL
  standard tap *
  page406_i6
#ISCELL
  standard tap *
  page406_i7
#ISCELL
  standard tap *
  page406_i8
#ISCELL
  standard tap *
  page406_i9
